FILE_TYPE = MULTI_PHYS_TABLE;

PART 'PI3EQX12902AZLEX'

{========================================================================================}
:VALUE              | PART_TYPE | MATERIAL | PART_NUMBER    = STANDARD | LIFECYCLE     | PART_NUMBER   | JEDEC_TYPE              | DESCRIPTION                           | MANUFTR | MANUF_PN           | RD_CMPLS_LVL | CMPLS_LVL | FROM_PJ    | CLASS | DIP_SMD | DATA                       | EE_CHECK_LIST | FP_ECN | PSL | CREATOR | STATUS | MSD  | ESD_CDM  | ESD_HBM | ESD_MM | PIN_LENGTH_SHORT_PIN | PIN_LENGTH_LONG_PIN | CREATEDAY  ;
{========================================================================================}
 'PI3EQX12902AZLEX' | 'SMLF'    | 'IC'     | 'AL012902001'(!) = ''       | ''               | 'AL012902001' |'TQFN30_TH_0-4_4-5X2-5'| 'IC OTHER(30P)PI3EQX12902AZLEX(TQFN)' | 'PIM'   | 'PI3EQX12902AZLEX' | 'EP(V1)'     | ''        | 'MF5-KYLE' | 'IC'  | ''      | 'PIM_PI3EQX12902AZLEX.pdf' | ''            | ''     | ''  | ''      | ''     | 'NA' | '+-500V' | '+-2kV' | 'NA'   | '0 MILS'             | '0 MILS'            | '20170824'
 'PI3EQX12902AZLEX' | 'SMLF'    | 'EMPTY'  | 'AL012902001'(!) = ''       | ''               | 'AL012902001' |'TQFN30_TH_0-4_4-5X2-5'| 'IC OTHER(30P)PI3EQX12902AZLEX(TQFN)' | 'PIM'   | 'PI3EQX12902AZLEX' | 'EP(V1)'     | ''        | 'MF5-KYLE' | 'IC'  | ''      | 'PIM_PI3EQX12902AZLEX.pdf' | ''            | ''     | ''  | ''      | ''     | 'NA' | '+-500V' | '+-2kV' | 'NA'   | '0 MILS'             | '0 MILS'            | '20170824'

END_PART

END.

